(kicad_pcb
	(version 20260206)
	(generator "pcbnew")
	(generator_version "10.0")
	(general
		(thickness 1.6)
		(legacy_teardrops no)
	)
	(paper "A4")
	(title_block
		(title "timecard-production-celestica-r4006 — R4006-B0001-02_R01.brd")
		(comment 1 "Time Appliance Project (Time Card) / footprints 418-422 of 1113")
	)
	(layers
		(0 "F.Cu" signal "TOP")
		(4 "In1.Cu" signal "L02_GND1")
		(6 "In2.Cu" signal "L03_SIG1")
		(8 "In3.Cu" signal "L04_GND2")
		(10 "In4.Cu" signal "L05_VCC1")
		(12 "In5.Cu" signal "L06_VCC2")
		(14 "In6.Cu" signal "L07_GND3")
		(16 "In7.Cu" signal "L08_SIG2")
		(18 "In8.Cu" signal "L09_GND4")
		(2 "B.Cu" signal "BOTTOM")
		(9 "F.Adhes" user "F.Adhesive")
		(11 "B.Adhes" user "B.Adhesive")
		(13 "F.Paste" user "Package Geometry/Pastemask Top")
		(15 "B.Paste" user "Package Geometry/Pastemask Bottom")
		(5 "F.SilkS" user "Ref Des/Silkscreen Top")
		(7 "B.SilkS" user "Ref Des/Silkscreen Bottom")
		(1 "F.Mask" user "Board Geometry/Soldermask Top")
		(3 "B.Mask" user "Board Geometry/Soldermask Bottom")
		(17 "Dwgs.User" user "User.Drawings")
		(19 "Cmts.User" user "User.Comments")
		(21 "Eco1.User" user "User.Eco1")
		(23 "Eco2.User" user "User.Eco2")
		(25 "Edge.Cuts" user "Board Geometry/Outline")
		(27 "Margin" user)
		(31 "F.CrtYd" user "Package Geometry/Place Bound Top")
		(29 "B.CrtYd" user "Package Geometry/Place Bound Bottom")
		(35 "F.Fab" user "Ref Des/Assembly Top")
		(33 "B.Fab" user "Ref Des/Assembly Bottom")
	)
	(footprint ""
		(layer "F.Cu")
		(at 11.557 -28.06446 -90)
		(property "Reference" "R122"
			(at 0.50546 2.11963 90)
			(unlocked yes)
			(layer "F.SilkS")
			(effects
				(font
					(size 0.7874 0.5842)
					(thickness 0.1524)
				)
			)
		)
		(property "Value" "VAL*"
			(at 0.02032 2.13233 270)
			(unlocked yes)
			(layer "F.Fab")
			(hide yes)
			(effects
				(font
					(size 0.7874 0.5842)
					(thickness 0.1524)
				)
			)
		)
		(property "Tolerance" "TOL*"
			(at 0.044704 3.05435 270)
			(unlocked yes)
			(layer "Cmts.User")
			(hide yes)
			(effects
				(font
					(size 0.7874 0.5842)
					(thickness 0.1524)
				)
			)
		)
		(property "User Part Number" "PARTNUM*"
			(at 0.02032 4.024884 270)
			(unlocked yes)
			(layer "Cmts.User")
			(hide yes)
			(effects
				(font
					(size 0.7874 0.5842)
					(thickness 0.1524)
				)
			)
		)
		(property "Device Type" "RESISTOR-G155-149R9-01,49.9OHMA"
			(at 0.008382 1.210564 270)
			(unlocked yes)
			(layer "F.Fab")
			(hide yes)
			(effects
				(font
					(size 0.7874 0.5842)
					(thickness 0.1524)
				)
			)
		)
		(duplicate_pad_numbers_are_jumpers no)
		(fp_line
			(start -1.143 0.5588)
			(end 1.143 0.5588)
			(stroke
				(width 0.1)
				(type default)
			)
			(layer "F.SilkS")
		)
		(fp_line
			(start 1.143 0.5588)
			(end 1.143 -0.5588)
			(stroke
				(width 0.1)
				(type default)
			)
			(layer "F.SilkS")
		)
		(fp_line
			(start -1.143 -0.5588)
			(end -1.143 0.5588)
			(stroke
				(width 0.1)
				(type default)
			)
			(layer "F.SilkS")
		)
		(fp_line
			(start 1.143 -0.5588)
			(end -1.143 -0.5588)
			(stroke
				(width 0.1)
				(type default)
			)
			(layer "F.SilkS")
		)
		(fp_poly
			(pts
				(xy -1.143 0.5588) (xy 1.143 0.5588) (xy 1.143 -0.5588) (xy -1.143 -0.5588)
			)
			(stroke
				(width 0)
				(type default)
			)
			(fill no)
			(layer "F.CrtYd")
		)
		(fp_line
			(start -0.508 0.3048)
			(end 0.508 0.3048)
			(stroke
				(width 0.1)
				(type default)
			)
			(layer "F.Fab")
		)
		(fp_line
			(start 0.508 0.3048)
			(end 0.508 -0.3048)
			(stroke
				(width 0.1)
				(type default)
			)
			(layer "F.Fab")
		)
		(fp_line
			(start -0.508 -0.3048)
			(end -0.508 0.3048)
			(stroke
				(width 0.1)
				(type default)
			)
			(layer "F.Fab")
		)
		(fp_line
			(start 0.508 -0.3048)
			(end -0.508 -0.3048)
			(stroke
				(width 0.1)
				(type default)
			)
			(layer "F.Fab")
		)
		(pad "1" smd rect
			(at -0.5334 0 270)
			(size 0.7112 0.6096)
			(layers "F.Cu" "F.Mask" "F.Paste")
			(net "BF_SMA3_SIG_IO_CONN")
		)
		(pad "2" smd rect
			(at 0.5334 0 270)
			(size 0.7112 0.6096)
			(layers "F.Cu" "F.Mask" "F.Paste")
			(net "SMA3_SIG_IO_CONN")
		)
		(zone
			(layer "F.Cu")
			(hatch none 0.5)
			(connect_pads
				(clearance 0)
			)
			(min_thickness 0.25)
			(keepout
				(tracks allowed)
				(vias not_allowed)
				(pads allowed)
				(copperpour not_allowed)
				(footprints allowed)
			)
			(placement
				(enabled no)
				(sheetname "")
			)
			(fill
				(thermal_gap 0.5)
				(thermal_bridge_width 0.5)
				(island_removal_mode 0)
			)
			(polygon
				(pts
					(xy 11.2522 -28.14066) (xy 11.2522 -27.98826) (xy 11.8618 -27.98826) (xy 11.8618 -28.14066)
				)
			)
		)
		(zone
			(layer "F.Cu")
			(hatch none 0.5)
			(connect_pads
				(clearance 0)
			)
			(min_thickness 0.25)
			(keepout
				(tracks not_allowed)
				(vias allowed)
				(pads allowed)
				(copperpour not_allowed)
				(footprints allowed)
			)
			(placement
				(enabled no)
				(sheetname "")
			)
			(fill
				(thermal_gap 0.5)
				(thermal_bridge_width 0.5)
				(island_removal_mode 0)
			)
			(polygon
				(pts
					(xy 11.2522 -28.14066) (xy 11.2522 -27.98826) (xy 11.8618 -27.98826) (xy 11.8618 -28.14066)
				)
			)
		)
	)
	(footprint ""
		(layer "F.Cu")
		(at 56.388 -129.032)
		(property "Reference" "SP81"
			(at 0 0 0)
			(layer "F.SilkS")
			(hide yes)
			(effects
				(font
					(size 1.27 1.27)
				)
			)
		)
		(property "Value" ""
			(at 0 0 0)
			(layer "F.Fab")
			(effects
				(font
					(size 1.27 1.27)
				)
			)
		)
		(duplicate_pad_numbers_are_jumpers no)
	)
	(footprint ""
		(layer "F.Cu")
		(at 71.1454 -15.367)
		(property "Reference" "U3"
			(at -0.127 -2.11963 0)
			(unlocked yes)
			(layer "F.SilkS")
			(effects
				(font
					(size 0.7874 0.5842)
					(thickness 0.1524)
				)
			)
		)
		(property "Value" ""
			(at 0 0 0)
			(layer "F.Fab")
			(effects
				(font
					(size 1.27 1.27)
				)
			)
		)
		(property "Device Type" "74LVC1G07_SC70_5-G220-10017-01"
			(at 0.4064 2.05867 0)
			(unlocked yes)
			(layer "F.Fab")
			(hide yes)
			(effects
				(font
					(size 0.7874 0.5842)
					(thickness 0.1524)
				)
			)
		)
		(property "User Part Number" "PARTNUM*"
			(at 0.381 2.97307 0)
			(unlocked yes)
			(layer "Cmts.User")
			(hide yes)
			(effects
				(font
					(size 0.7874 0.5842)
					(thickness 0.1524)
				)
			)
		)
		(duplicate_pad_numbers_are_jumpers no)
		(fp_line
			(start -1.9304 -1.069086)
			(end -1.9304 1.069086)
			(stroke
				(width 0.1)
				(type default)
			)
			(layer "F.SilkS")
		)
		(fp_line
			(start -1.9304 1.069086)
			(end -0.952754 1.069086)
			(stroke
				(width 0.1)
				(type default)
			)
			(layer "F.SilkS")
		)
		(fp_line
			(start -0.952754 -1.32842)
			(end -0.952754 -1.069086)
			(stroke
				(width 0.1)
				(type default)
			)
			(layer "F.SilkS")
		)
		(fp_line
			(start -0.952754 -1.069086)
			(end -1.9304 -1.069086)
			(stroke
				(width 0.1)
				(type default)
			)
			(layer "F.SilkS")
		)
		(fp_line
			(start -0.952754 1.069086)
			(end -0.952754 1.32842)
			(stroke
				(width 0.1)
				(type default)
			)
			(layer "F.SilkS")
		)
		(fp_line
			(start -0.952754 1.32842)
			(end 0.952754 1.32842)
			(stroke
				(width 0.1)
				(type default)
			)
			(layer "F.SilkS")
		)
		(fp_line
			(start 0.952754 -1.32842)
			(end -0.952754 -1.32842)
			(stroke
				(width 0.1)
				(type default)
			)
			(layer "F.SilkS")
		)
		(fp_line
			(start 0.952754 -1.069086)
			(end 0.952754 -1.32842)
			(stroke
				(width 0.1)
				(type default)
			)
			(layer "F.SilkS")
		)
		(fp_line
			(start 0.952754 1.069086)
			(end 1.9304 1.069086)
			(stroke
				(width 0.1)
				(type default)
			)
			(layer "F.SilkS")
		)
		(fp_line
			(start 0.952754 1.32842)
			(end 0.952754 1.069086)
			(stroke
				(width 0.1)
				(type default)
			)
			(layer "F.SilkS")
		)
		(fp_line
			(start 1.9304 -1.069086)
			(end 0.952754 -1.069086)
			(stroke
				(width 0.1)
				(type default)
			)
			(layer "F.SilkS")
		)
		(fp_line
			(start 1.9304 1.069086)
			(end 1.9304 -1.069086)
			(stroke
				(width 0.1)
				(type default)
			)
			(layer "F.SilkS")
		)
		(fp_poly
			(pts
				(arc
					(start -2.196592 -0.75438)
					(mid -2.958592 -0.75438)
					(end -2.196592 -0.75438)
				)
			)
			(stroke
				(width 0)
				(type default)
			)
			(fill yes)
			(layer "F.SilkS")
		)
		(fp_rect
			(start -2.1844 1.58242)
			(end 2.1844 -1.58242)
			(stroke
				(width 0)
				(type default)
			)
			(fill no)
			(layer "F.CrtYd")
		)
		(fp_line
			(start -0.698754 -1.07442)
			(end 0.698754 -1.07442)
			(stroke
				(width 0.1)
				(type default)
			)
			(layer "F.Fab")
		)
		(fp_line
			(start -0.698754 -0.774954)
			(end -0.698754 -1.07442)
			(stroke
				(width 0.1)
				(type default)
			)
			(layer "F.Fab")
		)
		(fp_line
			(start -0.698754 -0.525018)
			(end -0.698754 -0.124968)
			(stroke
				(width 0.1)
				(type default)
			)
			(layer "F.Fab")
		)
		(fp_line
			(start -0.698754 0.124968)
			(end -0.698754 0.525018)
			(stroke
				(width 0.1)
				(type default)
			)
			(layer "F.Fab")
		)
		(fp_line
			(start -0.698754 0.774954)
			(end -0.698754 1.07442)
			(stroke
				(width 0.1)
				(type default)
			)
			(layer "F.Fab")
		)
		(fp_line
			(start -0.698754 1.07442)
			(end 0.698754 1.07442)
			(stroke
				(width 0.1)
				(type default)
			)
			(layer "F.Fab")
		)
		(fp_line
			(start -0.450088 1.07442)
			(end -0.450088 -1.07442)
			(stroke
				(width 0.1)
				(type default)
			)
			(layer "F.Fab")
		)
		(fp_line
			(start 0.450088 -1.07442)
			(end 0.450088 1.07442)
			(stroke
				(width 0.1)
				(type default)
			)
			(layer "F.Fab")
		)
		(fp_line
			(start 0.698754 -1.07442)
			(end 0.698754 -0.774954)
			(stroke
				(width 0.1)
				(type default)
			)
			(layer "F.Fab")
		)
		(fp_line
			(start 0.698754 -0.525018)
			(end 0.698754 0.525018)
			(stroke
				(width 0.1)
				(type default)
			)
			(layer "F.Fab")
		)
		(fp_line
			(start 0.698754 1.07442)
			(end 0.698754 0.774954)
			(stroke
				(width 0.1)
				(type default)
			)
			(layer "F.Fab")
		)
		(fp_rect
			(start -1.198626 -0.525018)
			(end -0.6985 -0.774954)
			(stroke
				(width 0)
				(type default)
			)
			(fill no)
			(layer "F.Fab")
		)
		(fp_rect
			(start -1.198626 0.124968)
			(end -0.6985 -0.124968)
			(stroke
				(width 0)
				(type default)
			)
			(fill no)
			(layer "F.Fab")
		)
		(fp_rect
			(start -1.198626 0.774954)
			(end -0.6985 0.525018)
			(stroke
				(width 0)
				(type default)
			)
			(fill no)
			(layer "F.Fab")
		)
		(fp_rect
			(start 0.6985 -0.525018)
			(end 1.198626 -0.774954)
			(stroke
				(width 0)
				(type default)
			)
			(fill no)
			(layer "F.Fab")
		)
		(fp_rect
			(start 0.6985 0.774954)
			(end 1.198626 0.525018)
			(stroke
				(width 0)
				(type default)
			)
			(fill no)
			(layer "F.Fab")
		)
		(fp_poly
			(pts
				(arc
					(start -1.942592 -0.75438)
					(mid -2.704592 -0.75438)
					(end -1.942592 -0.75438)
				)
			)
			(stroke
				(width 0)
				(type default)
			)
			(fill yes)
			(layer "F.Fab")
		)
		(fp_text user "3"
			(at -2.413 0.797306 0)
			(unlocked yes)
			(layer "F.SilkS")
			(effects
				(font
					(size 0.7874 0.5842)
					(thickness 0.1524)
				)
			)
		)
		(fp_text user "5"
			(at 2.413 -0.599948 0)
			(unlocked yes)
			(layer "F.SilkS")
			(effects
				(font
					(size 0.7874 0.5842)
					(thickness 0.1524)
				)
			)
		)
		(fp_text user "4"
			(at 2.442972 0.7747 0)
			(unlocked yes)
			(layer "F.SilkS")
			(effects
				(font
					(size 0.7874 0.5842)
					(thickness 0.1524)
				)
			)
		)
		(fp_text user "3"
			(at -2.159 0.797306 0)
			(unlocked yes)
			(layer "F.Fab")
			(effects
				(font
					(size 0.7874 0.5842)
					(thickness 0.1524)
				)
			)
		)
		(fp_text user "5"
			(at 2.159 -0.599948 0)
			(unlocked yes)
			(layer "F.Fab")
			(effects
				(font
					(size 0.7874 0.5842)
					(thickness 0.1524)
				)
			)
		)
		(fp_text user "4"
			(at 2.188972 0.7747 0)
			(unlocked yes)
			(layer "F.Fab")
			(effects
				(font
					(size 0.7874 0.5842)
					(thickness 0.1524)
				)
			)
		)
		(pad "1" smd rect
			(at -1.1938 -0.649986 90)
			(size 0.3302 0.9652)
			(layers "F.Cu" "F.Mask" "F.Paste")
			(net "Net_761")
		)
		(pad "2" smd rect
			(at -1.1938 0 90)
			(size 0.3302 0.9652)
			(layers "F.Cu" "F.Mask" "F.Paste")
			(net "PCIE_CONN_PERST_N")
		)
		(pad "3" smd rect
			(at -1.1938 0.649986 90)
			(size 0.3302 0.9652)
			(layers "F.Cu" "F.Mask" "F.Paste")
			(net "SG")
		)
		(pad "4" smd rect
			(at 1.1938 0.649986 90)
			(size 0.3302 0.9652)
			(layers "F.Cu" "F.Mask" "F.Paste")
			(net "BF_PCIE_PERST_N")
		)
		(pad "5" smd rect
			(at 1.1938 -0.649986 90)
			(size 0.3302 0.9652)
			(layers "F.Cu" "F.Mask" "F.Paste")
			(net "XP3R3V_FPGA")
		)
		(zone
			(layer "F.Cu")
			(hatch none 0.5)
			(connect_pads
				(clearance 0)
			)
			(min_thickness 0.25)
			(keepout
				(tracks allowed)
				(vias not_allowed)
				(pads allowed)
				(copperpour not_allowed)
				(footprints allowed)
			)
			(placement
				(enabled no)
				(sheetname "")
			)
			(fill
				(thermal_gap 0.5)
				(thermal_bridge_width 0.5)
				(island_removal_mode 0)
			)
			(polygon
				(pts
					(xy 70.5104 -14.3637) (xy 71.7804 -14.3637) (xy 71.7804 -16.3703) (xy 70.5104 -16.3703)
				)
			)
		)
	)
	(footprint ""
		(layer "F.Cu")
		(at 91.5416 -44.868846 -90)
		(property "Reference" "R104"
			(at -0.597154 -1.44907 90)
			(unlocked yes)
			(layer "F.SilkS")
			(effects
				(font
					(size 0.7874 0.5842)
					(thickness 0.1524)
				)
			)
		)
		(property "Value" "VAL*"
			(at 0.02032 2.13233 270)
			(unlocked yes)
			(layer "F.Fab")
			(hide yes)
			(effects
				(font
					(size 0.7874 0.5842)
					(thickness 0.1524)
				)
			)
		)
		(property "Device Type" "RESISTOR-G155-14701-01,4.7KOHMA"
			(at 0.008382 1.210564 270)
			(unlocked yes)
			(layer "F.Fab")
			(hide yes)
			(effects
				(font
					(size 0.7874 0.5842)
					(thickness 0.1524)
				)
			)
		)
		(property "User Part Number" "PARTNUM*"
			(at 0.02032 4.024884 270)
			(unlocked yes)
			(layer "Cmts.User")
			(hide yes)
			(effects
				(font
					(size 0.7874 0.5842)
					(thickness 0.1524)
				)
			)
		)
		(property "Tolerance" "TOL*"
			(at 0.044704 3.05435 270)
			(unlocked yes)
			(layer "Cmts.User")
			(hide yes)
			(effects
				(font
					(size 0.7874 0.5842)
					(thickness 0.1524)
				)
			)
		)
		(duplicate_pad_numbers_are_jumpers no)
		(fp_line
			(start -1.143 0.5588)
			(end 1.143 0.5588)
			(stroke
				(width 0.1)
				(type default)
			)
			(layer "F.SilkS")
		)
		(fp_line
			(start 1.143 0.5588)
			(end 1.143 -0.5588)
			(stroke
				(width 0.1)
				(type default)
			)
			(layer "F.SilkS")
		)
		(fp_line
			(start -1.143 -0.5588)
			(end -1.143 0.5588)
			(stroke
				(width 0.1)
				(type default)
			)
			(layer "F.SilkS")
		)
		(fp_line
			(start 1.143 -0.5588)
			(end -1.143 -0.5588)
			(stroke
				(width 0.1)
				(type default)
			)
			(layer "F.SilkS")
		)
		(fp_rect
			(start -1.143 -0.5588)
			(end 1.143 0.5588)
			(stroke
				(width 0)
				(type default)
			)
			(fill no)
			(layer "F.CrtYd")
		)
		(fp_line
			(start -0.508 0.3048)
			(end 0.508 0.3048)
			(stroke
				(width 0.1)
				(type default)
			)
			(layer "F.Fab")
		)
		(fp_line
			(start 0.508 0.3048)
			(end 0.508 -0.3048)
			(stroke
				(width 0.1)
				(type default)
			)
			(layer "F.Fab")
		)
		(fp_line
			(start -0.508 -0.3048)
			(end -0.508 0.3048)
			(stroke
				(width 0.1)
				(type default)
			)
			(layer "F.Fab")
		)
		(fp_line
			(start 0.508 -0.3048)
			(end -0.508 -0.3048)
			(stroke
				(width 0.1)
				(type default)
			)
			(layer "F.Fab")
		)
		(pad "1" smd rect
			(at -0.5334 0 270)
			(size 0.7112 0.6096)
			(layers "F.Cu" "F.Mask" "F.Paste")
			(net "UNNAMED_527_RESISTOR_I126_1")
		)
		(pad "2" smd rect
			(at 0.5334 0 270)
			(size 0.7112 0.6096)
			(layers "F.Cu" "F.Mask" "F.Paste")
			(net "SG")
		)
		(zone
			(layer "F.Cu")
			(hatch none 0.5)
			(connect_pads
				(clearance 0)
			)
			(min_thickness 0.25)
			(keepout
				(tracks allowed)
				(vias not_allowed)
				(pads allowed)
				(copperpour not_allowed)
				(footprints allowed)
			)
			(placement
				(enabled no)
				(sheetname "")
			)
			(fill
				(thermal_gap 0.5)
				(thermal_bridge_width 0.5)
				(island_removal_mode 0)
			)
			(polygon
				(pts
					(xy 91.8464 -44.945046) (xy 91.2368 -44.945046) (xy 91.2368 -44.792646) (xy 91.8464 -44.792646)
				)
			)
		)
	)
	(footprint ""
		(layer "F.Cu")
		(at 119.761 -24.511)
		(property "Reference" "R485"
			(at -2.794 -0.08763 0)
			(unlocked yes)
			(layer "F.SilkS")
			(effects
				(font
					(size 0.7874 0.5842)
					(thickness 0.1524)
				)
			)
		)
		(property "Value" "VAL*"
			(at 0.02032 2.13233 0)
			(unlocked yes)
			(layer "F.Fab")
			(hide yes)
			(effects
				(font
					(size 0.7874 0.5842)
					(thickness 0.1524)
				)
			)
		)
		(property "Tolerance" "TOL*"
			(at 0.044704 3.05435 0)
			(unlocked yes)
			(layer "Cmts.User")
			(hide yes)
			(effects
				(font
					(size 0.7874 0.5842)
					(thickness 0.1524)
				)
			)
		)
		(property "User Part Number" "PARTNUM*"
			(at 0.02032 4.024884 0)
			(unlocked yes)
			(layer "Cmts.User")
			(hide yes)
			(effects
				(font
					(size 0.7874 0.5842)
					(thickness 0.1524)
				)
			)
		)
		(property "Device Type" "RESISTOR-G155-133R0-01,33OHM,1%"
			(at 0.008382 1.210564 0)
			(unlocked yes)
			(layer "F.Fab")
			(hide yes)
			(effects
				(font
					(size 0.7874 0.5842)
					(thickness 0.1524)
				)
			)
		)
		(duplicate_pad_numbers_are_jumpers no)
		(fp_line
			(start -1.143 -0.5588)
			(end -1.143 0.5588)
			(stroke
				(width 0.1)
				(type default)
			)
			(layer "F.SilkS")
		)
		(fp_line
			(start -1.143 0.5588)
			(end 1.143 0.5588)
			(stroke
				(width 0.1)
				(type default)
			)
			(layer "F.SilkS")
		)
		(fp_line
			(start 1.143 -0.5588)
			(end -1.143 -0.5588)
			(stroke
				(width 0.1)
				(type default)
			)
			(layer "F.SilkS")
		)
		(fp_line
			(start 1.143 0.5588)
			(end 1.143 -0.5588)
			(stroke
				(width 0.1)
				(type default)
			)
			(layer "F.SilkS")
		)
		(fp_poly
			(pts
				(xy -1.143 0.5588) (xy 1.143 0.5588) (xy 1.143 -0.5588) (xy -1.143 -0.5588)
			)
			(stroke
				(width 0)
				(type default)
			)
			(fill no)
			(layer "F.CrtYd")
		)
		(fp_line
			(start -0.508 -0.3048)
			(end -0.508 0.3048)
			(stroke
				(width 0.1)
				(type default)
			)
			(layer "F.Fab")
		)
		(fp_line
			(start -0.508 0.3048)
			(end 0.508 0.3048)
			(stroke
				(width 0.1)
				(type default)
			)
			(layer "F.Fab")
		)
		(fp_line
			(start 0.508 -0.3048)
			(end -0.508 -0.3048)
			(stroke
				(width 0.1)
				(type default)
			)
			(layer "F.Fab")
		)
		(fp_line
			(start 0.508 0.3048)
			(end 0.508 -0.3048)
			(stroke
				(width 0.1)
				(type default)
			)
			(layer "F.Fab")
		)
		(pad "1" smd rect
			(at -0.5334 0)
			(size 0.7112 0.6096)
			(layers "F.Cu" "F.Mask" "F.Paste")
			(net "FPGA_OUT_MUX3_SEL")
		)
		(pad "2" smd rect
			(at 0.5334 0)
			(size 0.7112 0.6096)
			(layers "F.Cu" "F.Mask" "F.Paste")
			(net "MUX3_SEL")
		)
		(zone
			(layer "F.Cu")
			(hatch none 0.5)
			(connect_pads
				(clearance 0)
			)
			(min_thickness 0.25)
			(keepout
				(tracks not_allowed)
				(vias allowed)
				(pads allowed)
				(copperpour not_allowed)
				(footprints allowed)
			)
			(placement
				(enabled no)
				(sheetname "")
			)
			(fill
				(thermal_gap 0.5)
				(thermal_bridge_width 0.5)
				(island_removal_mode 0)
			)
			(polygon
				(pts
					(xy 119.6848 -24.2062) (xy 119.8372 -24.2062) (xy 119.8372 -24.8158) (xy 119.6848 -24.8158)
				)
			)
		)
		(zone
			(layer "F.Cu")
			(hatch none 0.5)
			(connect_pads
				(clearance 0)
			)
			(min_thickness 0.25)
			(keepout
				(tracks allowed)
				(vias not_allowed)
				(pads allowed)
				(copperpour not_allowed)
				(footprints allowed)
			)
			(placement
				(enabled no)
				(sheetname "")
			)
			(fill
				(thermal_gap 0.5)
				(thermal_bridge_width 0.5)
				(island_removal_mode 0)
			)
			(polygon
				(pts
					(xy 119.6848 -24.2062) (xy 119.8372 -24.2062) (xy 119.8372 -24.8158) (xy 119.6848 -24.8158)
				)
			)
		)
	)
)
